FILE_TYPE = MACRO_DRAWING;
SET COLOR_WIRE YELLOW;
SET COLOR_PROP ORANGE;
SET COLOR_DOT WHITE;
SET COLOR_ARC YELLOW;
SET COLOR_BODY GREEN;
SET COLOR_NOTE PURPLE;
SET PROP_DISPLAY VALUE;
SET PAGE_NUMBER P284;
FORCEADD QUANTA_TITLE_BLOCK_C..1
(600 950);
FORCEPROP 1 LAST CUSTOM_TXT_CDS <NAME_2>
J 0
(-2575 1000);
FORCEPROP 1 LAST CUSTOM_TXT_CDS <NAME_1>
J 0
(-2575 1125);
FORCEPROP 1 LAST CUSTOM_TXT_CDS <Q_NUMBER>
J 0
(-803 1053);
DISPLAY 1.212766 (-803 1053);
FORCEPROP 1 LAST CUSTOM_TXT_CDS <Q_PROJ>
J 0
(-1782 1052);
DISPLAY 1.212766 (-1782 1052);
FORCEPROP 1 LAST CUSTOM_TXT_CDS <Q_REV>
J 0
(416 1053);
DISPLAY 1.212766 (416 1053);
FORCEPROP 1 LAST CUSTOM_TXT_CDS <CON_LAST_MODIFIED>
J 0
(-1285 965);
DISPLAY 0.978723 (-1285 965);
FORCEPROP 1 LAST CUSTOM_TXT_CDS <CON_PAGE_NUM> OF <CON_TOTAL_PAGES>
J 0
(154 968);
DISPLAY 0.978723 (154 968);
FORCEPROP 1 LAST Q_TITLE BLANK
J 0
(-8766 976);
DISPLAY 2.446809 (-8766 976);
PAINT GREEN (-8766 976);
FORCEPROP 1 LAST Q_DEPT 
J 1
(-3163 999);
DISPLAY 1.957447 (-3163 999);
PAINT GREEN (-3163 999);
FORCEPROP 2 LAST CDS_XR_PAGE_TITLE CR-298 : @S9S_MB_2U_LIB.S9S_MB_2U(SCH_1):PAGE298
J 0
(-7290 6200);
DISPLAY 0.638298 (-7290 6200);
PAINT PINK (-7290 6200);
DISPLAY INVISIBLE (-7290 6200);
FORCEPROP 1 LAST COMMENT_BODY TRUE
J 0
(612 937);
DISPLAY 0.978723 (612 937);
PAINT GREEN (612 937);
DISPLAY INVISIBLE (612 937);
FORCEPROP 2 LAST CDS_LIB pure_quanta
J 0
(600 950);
DISPLAY INVISIBLE (600 950);
FORCEPROP 1 LAST CDS_LMAN_SYM_OUTLINE -9475,6775,100,-125
J 0
(600 950);
DISPLAY 0.468085 (600 950);
PAINT GREEN (600 950);
DISPLAY INVISIBLE (600 950);
FORCEPROP 2 LAST PAGE_BORDER TRUE
J 0
(-7290 6200);
DISPLAY 0.638298 (-7290 6200);
PAINT PINK (-7290 6200);
DISPLAY INVISIBLE (-7290 6200);
FORCEPROP 2 LAST CUSTOM_TXT_CDS <XR_PAGE_TITLE>
J 0
(-7290 6200);
DISPLAY 0.638298 (-7290 6200);
PAINT PINK (-7290 6200);
DISPLAY INVISIBLE (-7290 6200);
FORCEPROP 0 LAST CDS_CON_LAST_MODIFIED Thu Aug 24 16:17:09 2023
J 0
(-1285 965);
DISPLAY INVISIBLE (-1285 965);
QUIT
